#ISCELL
  mstr_misc prelim *
  *
#ISCELL
  mstr_symbols design_note *
  *
#ISCELL
  mstr_symbols intel_corp_bpage *
  *
#ISCELL
  mstr_standard offpage *
  page28_i1
#ISCELL
  mstr_standard tap *
  page28_i10
#ISCELL
  mstr_standard tap *
  page28_i100
#ISCELL
  mstr_standard tap *
  page28_i101
#ISCELL
  mstr_standard tap *
  page28_i102
#ISCELL
  mstr_standard tap *
  page28_i103
#ISCELL
  mstr_standard tap *
  page28_i104
#ISCELL
  mstr_standard tap *
  page28_i105
#ISCELL
  mstr_standard tap *
  page28_i106
#ISCELL
  mstr_standard tap *
  page28_i107
#ISCELL
  mstr_standard tap *
  page28_i108
#ISCELL
  mstr_standard tap *
  page28_i109
#ISCELL
  mstr_standard tap *
  page28_i11
#ISCELL
  mstr_standard tap *
  page28_i110
#ISCELL
  mstr_standard tap *
  page28_i111
#ISCELL
  mstr_standard tap *
  page28_i112
#ISCELL
  mstr_standard tap *
  page28_i113
#ISCELL
  mstr_standard tap *
  page28_i114
#ISCELL
  mstr_standard tap *
  page28_i115
#ISCELL
  mstr_standard tap *
  page28_i116
#ISCELL
  mstr_standard tap *
  page28_i117
#ISCELL
  mstr_standard tap *
  page28_i118
#ISCELL
  mstr_standard tap *
  page28_i119
#ISCELL
  mstr_standard tap *
  page28_i12
#ISCELL
  mstr_standard tap *
  page28_i120
#ISCELL
  mstr_standard tap *
  page28_i121
#ISCELL
  mstr_standard tap *
  page28_i122
#ISCELL
  mstr_standard tap *
  page28_i123
#ISCELL
  mstr_standard tap *
  page28_i124
#ISCELL
  mstr_standard tap *
  page28_i125
#ISCELL
  mstr_standard tap *
  page28_i126
#ISCELL
  mstr_standard tap *
  page28_i127
#ISCELL
  mstr_standard tap *
  page28_i128
#ISCELL
  mstr_standard tap *
  page28_i129
#ISCELL
  mstr_standard tap *
  page28_i13
#ISCELL
  mstr_standard tap *
  page28_i130
#ISCELL
  mstr_standard tap *
  page28_i131
#ISCELL
  mstr_standard tap *
  page28_i132
#ISCELL
  mstr_standard tap *
  page28_i133
#ISCELL
  mstr_standard tap *
  page28_i134
#ISCELL
  mstr_standard tap *
  page28_i135
#ISCELL
  mstr_standard tap *
  page28_i136
#ISCELL
  mstr_standard tap *
  page28_i137
#ISCELL
  mstr_standard tap *
  page28_i138
#ISCELL
  mstr_standard tap *
  page28_i139
#ISCELL
  mstr_standard tap *
  page28_i14
#ISCELL
  mstr_standard tap *
  page28_i140
#ISCELL
  mstr_standard tap *
  page28_i141
#ISCELL
  mstr_standard tap *
  page28_i142
#ISCELL
  mstr_standard tap *
  page28_i143
#ISCELL
  mstr_standard tap *
  page28_i144
#ISCELL
  mstr_standard tap *
  page28_i145
#ISCELL
  mstr_standard tap *
  page28_i146
#ISCELL
  mstr_standard tap *
  page28_i147
#ISCELL
  mstr_standard offpage *
  page28_i148
#ISCELL
  mstr_standard offpage *
  page28_i149
#ISCELL
  mstr_standard tap *
  page28_i15
#ISCELL
  mstr_standard offpage *
  page28_i150
#ISCELL
  mstr_standard offpage *
  page28_i151
#ISCELL
  mstr_standard offpage *
  page28_i152
#ISCELL
  mstr_standard offpage *
  page28_i153
#ISCELL
  mstr_standard offpage *
  page28_i154
#ISCELL
  mstr_standard offpage *
  page28_i155
#ISCELL
  mstr_standard offpage *
  page28_i156
#ISCELL
  mstr_standard offpage *
  page28_i157
#ISCELL
  mstr_standard tap *
  page28_i158
#ISCELL
  mstr_standard tap *
  page28_i159
#ISCELL
  mstr_standard tap *
  page28_i16
#ISCELL
  mstr_standard tap *
  page28_i160
#ISCELL
  mstr_standard tap *
  page28_i161
#ISCELL
  mstr_standard tap *
  page28_i162
#ISCELL
  mstr_standard tap *
  page28_i163
#ISCELL
  mstr_standard tap *
  page28_i164
#ISCELL
  mstr_standard tap *
  page28_i165
#ISCELL
  mstr_standard tap *
  page28_i166
#ISCELL
  mstr_standard tap *
  page28_i167
#ISCELL
  mstr_standard tap *
  page28_i168
#ISCELL
  mstr_standard tap *
  page28_i169
#ISCELL
  mstr_standard tap *
  page28_i17
#ISCELL
  mstr_standard tap *
  page28_i170
#ISCELL
  mstr_standard offpage *
  page28_i171
#CELL
  chpset_lib skx_ext_b *
  page28_i172
#ISCELL
  mstr_standard tap *
  page28_i18
#ISCELL
  mstr_standard tap *
  page28_i19
#ISCELL
  mstr_standard offpage *
  page28_i2
#ISCELL
  mstr_standard tap *
  page28_i20
#ISCELL
  mstr_standard tap *
  page28_i21
#ISCELL
  mstr_standard tap *
  page28_i22
#ISCELL
  mstr_standard tap *
  page28_i23
#ISCELL
  mstr_standard tap *
  page28_i24
#ISCELL
  mstr_standard tap *
  page28_i25
#ISCELL
  mstr_standard tap *
  page28_i26
#ISCELL
  mstr_standard tap *
  page28_i27
#ISCELL
  mstr_standard tap *
  page28_i28
#ISCELL
  mstr_standard tap *
  page28_i29
#ISCELL
  mstr_standard offpage *
  page28_i3
#ISCELL
  mstr_standard tap *
  page28_i30
#ISCELL
  mstr_standard tap *
  page28_i32
#ISCELL
  mstr_standard tap *
  page28_i33
#ISCELL
  mstr_standard tap *
  page28_i34
#ISCELL
  mstr_standard tap *
  page28_i35
#ISCELL
  mstr_standard tap *
  page28_i36
#ISCELL
  mstr_standard tap *
  page28_i37
#ISCELL
  mstr_standard tap *
  page28_i38
#ISCELL
  mstr_standard tap *
  page28_i39
#ISCELL
  mstr_standard offpage *
  page28_i4
#ISCELL
  mstr_standard tap *
  page28_i40
#ISCELL
  mstr_standard tap *
  page28_i41
#ISCELL
  mstr_standard tap *
  page28_i42
#ISCELL
  mstr_standard tap *
  page28_i43
#ISCELL
  mstr_standard tap *
  page28_i44
#ISCELL
  mstr_standard tap *
  page28_i45
#ISCELL
  mstr_standard tap *
  page28_i46
#ISCELL
  mstr_standard tap *
  page28_i47
#ISCELL
  mstr_standard tap *
  page28_i48
#ISCELL
  mstr_standard tap *
  page28_i49
#ISCELL
  mstr_standard tap *
  page28_i5
#ISCELL
  mstr_standard tap *
  page28_i50
#ISCELL
  mstr_standard tap *
  page28_i51
#ISCELL
  mstr_standard tap *
  page28_i52
#ISCELL
  mstr_standard tap *
  page28_i53
#ISCELL
  mstr_standard tap *
  page28_i54
#ISCELL
  mstr_standard tap *
  page28_i55
#ISCELL
  mstr_standard tap *
  page28_i56
#ISCELL
  mstr_standard tap *
  page28_i57
#ISCELL
  mstr_standard tap *
  page28_i58
#ISCELL
  mstr_standard tap *
  page28_i59
#ISCELL
  mstr_standard tap *
  page28_i6
#ISCELL
  mstr_standard tap *
  page28_i60
#ISCELL
  mstr_standard tap *
  page28_i61
#ISCELL
  mstr_standard tap *
  page28_i62
#ISCELL
  mstr_standard tap *
  page28_i63
#ISCELL
  mstr_standard tap *
  page28_i64
#ISCELL
  mstr_standard tap *
  page28_i65
#ISCELL
  mstr_standard tap *
  page28_i66
#ISCELL
  mstr_standard tap *
  page28_i67
#ISCELL
  mstr_standard tap *
  page28_i68
#ISCELL
  mstr_standard tap *
  page28_i69
#ISCELL
  mstr_standard tap *
  page28_i7
#ISCELL
  mstr_standard tap *
  page28_i70
#ISCELL
  mstr_standard tap *
  page28_i71
#ISCELL
  mstr_standard tap *
  page28_i72
#ISCELL
  mstr_standard offpage *
  page28_i73
#ISCELL
  mstr_standard tap *
  page28_i74
#ISCELL
  mstr_standard tap *
  page28_i75
#ISCELL
  mstr_standard tap *
  page28_i76
#ISCELL
  mstr_standard tap *
  page28_i77
#ISCELL
  mstr_standard tap *
  page28_i78
#ISCELL
  mstr_standard tap *
  page28_i79
#ISCELL
  mstr_standard tap *
  page28_i8
#ISCELL
  mstr_standard tap *
  page28_i80
#ISCELL
  mstr_standard tap *
  page28_i81
#ISCELL
  mstr_standard tap *
  page28_i82
#ISCELL
  mstr_standard tap *
  page28_i83
#ISCELL
  mstr_standard tap *
  page28_i84
#ISCELL
  mstr_standard tap *
  page28_i85
#ISCELL
  mstr_standard tap *
  page28_i86
#ISCELL
  mstr_standard tap *
  page28_i87
#ISCELL
  mstr_standard tap *
  page28_i88
#ISCELL
  mstr_standard tap *
  page28_i89
#ISCELL
  mstr_standard tap *
  page28_i9
#ISCELL
  mstr_standard tap *
  page28_i90
#ISCELL
  mstr_standard tap *
  page28_i91
#ISCELL
  mstr_standard tap *
  page28_i92
#ISCELL
  mstr_standard tap *
  page28_i93
#ISCELL
  mstr_standard tap *
  page28_i94
#ISCELL
  mstr_standard tap *
  page28_i95
#ISCELL
  mstr_standard tap *
  page28_i96
#ISCELL
  mstr_standard tap *
  page28_i97
#ISCELL
  mstr_standard tap *
  page28_i98
#ISCELL
  mstr_standard tap *
  page28_i99
